# T6G (Grand Teton) — schematic netlist excerpt (pin names and nets, part order shuffled) for the footprints in the layout excerpt that follows; sources: Cadence DE-HDL packaged netlist, KiCad conversion of 04192023_DAF0TMB3IC0_F0TG_MB_C_brd_V02_OCP.brd

C2506  Q_CAP  22UF 4V 20% X6S  pkg C0402  page 74 : A = PVDD11_S3_P1 ; B = GND
R8242  Q_RES  1K 1% CHIP  pkg 0402LF  page 217 : A = P3V3_AUX ; B = PWRGD_PVDDIO_P1_R

(kicad_pcb
	(version 20260206)
	(generator "pcbnew")
	(generator_version "10.0")
	(general
		(thickness 1.6)
		(legacy_teardrops no)
	)
	(paper "A4")
	(title_block
		(title "04192023_DAF0TMB3IC0_F0TG_MB_C_brd_V02_OCP.brd")
		(comment 1 "Grand Teton / footprints 6825-6826 of 8354")
	)
	(layers
		(0 "F.Cu" signal "TOP")
		(4 "In1.Cu" signal "GND")
		(6 "In2.Cu" signal "IN1")
		(8 "In3.Cu" signal "GND1")
		(10 "In4.Cu" signal "IN2")
		(12 "In5.Cu" signal "GND2")
		(14 "In6.Cu" signal "IN3")
		(16 "In7.Cu" signal "GND3")
		(18 "In8.Cu" signal "VCC")
		(20 "In9.Cu" signal "VCC1")
		(22 "In10.Cu" signal "GND4")
		(24 "In11.Cu" signal "IN4")
		(26 "In12.Cu" signal "GND5")
		(28 "In13.Cu" signal "IN5")
		(30 "In14.Cu" signal "GND6")
		(32 "In15.Cu" signal "IN6")
		(34 "In16.Cu" signal "GND7")
		(2 "B.Cu" signal "BOTTOM")
		(9 "F.Adhes" user "F.Adhesive")
		(11 "B.Adhes" user "B.Adhesive")
		(13 "F.Paste" user "Package Geometry/Pastemask Top")
		(15 "B.Paste" user "Package Geometry/Pastemask Bottom")
		(5 "F.SilkS" user "Ref Des/Silkscreen Top")
		(7 "B.SilkS" user "Ref Des/Silkscreen Bottom")
		(1 "F.Mask" user "Board Geometry/Soldermask Top")
		(3 "B.Mask" user "Board Geometry/Soldermask Bottom")
		(17 "Dwgs.User" user "User.Drawings")
		(19 "Cmts.User" user "User.Comments")
		(21 "Eco1.User" user "User.Eco1")
		(23 "Eco2.User" user "User.Eco2")
		(25 "Edge.Cuts" user "Board Geometry/Outline")
		(27 "Margin" user)
		(31 "F.CrtYd" user "Package Geometry/Place Bound Top")
		(29 "B.CrtYd" user "Package Geometry/Place Bound Bottom")
		(35 "F.Fab" user "Ref Des/Assembly Top")
		(33 "B.Fab" user "Ref Des/Assembly Bottom")
	)
	(footprint ""
		(layer "B.Cu")
		(at 114.327178 -261.748016 90)
		(property "Reference" "C2506"
			(at 0 0 90)
			(layer "B.SilkS")
			(hide yes)
			(effects
				(font
					(size 1.27 1.27)
				)
				(justify mirror)
			)
		)
		(property "Value" ""
			(at 0 0 90)
			(layer "B.Fab")
			(effects
				(font
					(size 1.27 1.27)
				)
				(justify mirror)
			)
		)
		(duplicate_pad_numbers_are_jumpers no)
		(fp_line
			(start 0.7874 -0.4064)
			(end -0.7874 -0.4064)
			(stroke
				(width 0.1524)
				(type default)
			)
			(layer "B.SilkS")
		)
		(fp_line
			(start -0.7874 -0.4064)
			(end -0.7874 0.4064)
			(stroke
				(width 0.1524)
				(type default)
			)
			(layer "B.SilkS")
		)
		(fp_line
			(start 0.7874 0.4064)
			(end 0.7874 -0.4064)
			(stroke
				(width 0.1524)
				(type default)
			)
			(layer "B.SilkS")
		)
		(fp_line
			(start -0.7874 0.4064)
			(end 0.7874 0.4064)
			(stroke
				(width 0.1524)
				(type default)
			)
			(layer "B.SilkS")
		)
		(fp_line
			(start 0.67945 -0.305054)
			(end 0.12065 -0.305054)
			(stroke
				(width 0.1)
				(type default)
			)
			(layer "B.Fab")
		)
		(fp_line
			(start 0.12065 -0.305054)
			(end 0.12065 -0.2794)
			(stroke
				(width 0.1)
				(type default)
			)
			(layer "B.Fab")
		)
		(fp_line
			(start -0.12065 -0.3048)
			(end -0.67945 -0.3048)
			(stroke
				(width 0.1)
				(type default)
			)
			(layer "B.Fab")
		)
		(fp_line
			(start -0.67945 -0.3048)
			(end -0.67945 0.3048)
			(stroke
				(width 0.1)
				(type default)
			)
			(layer "B.Fab")
		)
		(fp_line
			(start 0.12065 -0.2794)
			(end -0.12065 -0.2794)
			(stroke
				(width 0.1)
				(type default)
			)
			(layer "B.Fab")
		)
		(fp_line
			(start -0.12065 -0.2794)
			(end -0.12065 -0.3048)
			(stroke
				(width 0.1)
				(type default)
			)
			(layer "B.Fab")
		)
		(fp_line
			(start 0.12065 0.2794)
			(end 0.12065 0.3048)
			(stroke
				(width 0.1)
				(type default)
			)
			(layer "B.Fab")
		)
		(fp_line
			(start -0.120396 0.2794)
			(end 0.12065 0.2794)
			(stroke
				(width 0.1)
				(type default)
			)
			(layer "B.Fab")
		)
		(fp_line
			(start 0.67945 0.3048)
			(end 0.67945 -0.305054)
			(stroke
				(width 0.1)
				(type default)
			)
			(layer "B.Fab")
		)
		(fp_line
			(start 0.12065 0.3048)
			(end 0.67945 0.3048)
			(stroke
				(width 0.1)
				(type default)
			)
			(layer "B.Fab")
		)
		(fp_line
			(start -0.120396 0.3048)
			(end -0.120396 0.2794)
			(stroke
				(width 0.1)
				(type default)
			)
			(layer "B.Fab")
		)
		(fp_line
			(start -0.67945 0.3048)
			(end -0.120396 0.3048)
			(stroke
				(width 0.1)
				(type default)
			)
			(layer "B.Fab")
		)
		(pad "1" smd circle
			(at 0.40005 0 270)
			(size 0 0)
			(layers "B.Cu" "B.Mask" "B.Paste")
			(net "PVDD11_S3_P1")
		)
		(pad "2" smd circle
			(at -0.40005 0 270)
			(size 0 0)
			(layers "B.Cu" "B.Mask" "B.Paste")
			(net "GND")
		)
	)
	(footprint ""
		(layer "B.Cu")
		(at 24.765 -362.204 180)
		(property "Reference" "R8242"
			(at 0 0 0)
			(layer "B.SilkS")
			(hide yes)
			(effects
				(font
					(size 1.27 1.27)
				)
				(justify mirror)
			)
		)
		(property "Value" ""
			(at 0 0 0)
			(layer "B.Fab")
			(effects
				(font
					(size 1.27 1.27)
				)
				(justify mirror)
			)
		)
		(duplicate_pad_numbers_are_jumpers no)
		(fp_line
			(start 0.7874 0.4064)
			(end 0.7874 -0.4064)
			(stroke
				(width 0.1524)
				(type default)
			)
			(layer "B.SilkS")
		)
		(fp_line
			(start 0.7874 -0.4064)
			(end -0.7874 -0.4064)
			(stroke
				(width 0.1524)
				(type default)
			)
			(layer "B.SilkS")
		)
		(fp_line
			(start -0.7874 0.4064)
			(end 0.7874 0.4064)
			(stroke
				(width 0.1524)
				(type default)
			)
			(layer "B.SilkS")
		)
		(fp_line
			(start -0.7874 -0.4064)
			(end -0.7874 0.4064)
			(stroke
				(width 0.1524)
				(type default)
			)
			(layer "B.SilkS")
		)
		(fp_line
			(start 0.67945 0.3048)
			(end 0.67945 -0.305054)
			(stroke
				(width 0.1)
				(type default)
			)
			(layer "B.Fab")
		)
		(fp_line
			(start 0.67945 -0.305054)
			(end 0.12065 -0.305054)
			(stroke
				(width 0.1)
				(type default)
			)
			(layer "B.Fab")
		)
		(fp_line
			(start 0.12065 0.3048)
			(end 0.67945 0.3048)
			(stroke
				(width 0.1)
				(type default)
			)
			(layer "B.Fab")
		)
		(fp_line
			(start 0.12065 0.2794)
			(end 0.12065 0.3048)
			(stroke
				(width 0.1)
				(type default)
			)
			(layer "B.Fab")
		)
		(fp_line
			(start 0.12065 -0.2794)
			(end -0.12065 -0.2794)
			(stroke
				(width 0.1)
				(type default)
			)
			(layer "B.Fab")
		)
		(fp_line
			(start 0.12065 -0.305054)
			(end 0.12065 -0.2794)
			(stroke
				(width 0.1)
				(type default)
			)
			(layer "B.Fab")
		)
		(fp_line
			(start -0.120396 0.3048)
			(end -0.120396 0.2794)
			(stroke
				(width 0.1)
				(type default)
			)
			(layer "B.Fab")
		)
		(fp_line
			(start -0.120396 0.2794)
			(end 0.12065 0.2794)
			(stroke
				(width 0.1)
				(type default)
			)
			(layer "B.Fab")
		)
		(fp_line
			(start -0.12065 -0.2794)
			(end -0.12065 -0.3048)
			(stroke
				(width 0.1)
				(type default)
			)
			(layer "B.Fab")
		)
		(fp_line
			(start -0.12065 -0.3048)
			(end -0.67945 -0.3048)
			(stroke
				(width 0.1)
				(type default)
			)
			(layer "B.Fab")
		)
		(fp_line
			(start -0.67945 0.3048)
			(end -0.120396 0.3048)
			(stroke
				(width 0.1)
				(type default)
			)
			(layer "B.Fab")
		)
		(fp_line
			(start -0.67945 -0.3048)
			(end -0.67945 0.3048)
			(stroke
				(width 0.1)
				(type default)
			)
			(layer "B.Fab")
		)
		(pad "1" smd circle
			(at 0.40005 0)
			(size 0 0)
			(layers "B.Cu" "B.Mask" "B.Paste")
			(net "P3V3_AUX")
		)
		(pad "2" smd circle
			(at -0.40005 0)
			(size 0 0)
			(layers "B.Cu" "B.Mask" "B.Paste")
			(net "PWRGD_PVDDIO_P1_R")
		)
	)
)
